(kicad_pcb
	(version 20241229)
	(generator "pcbnew")
	(generator_version "9.0")
	(general
		(thickness 1.294)
		(legacy_teardrops no)
	)
	(paper "A3")
	(title_block
		(title "Kintex 410T devboard")
		(date "2024-04-03")
		(rev "1.1.2")
		(comment 9 "footprints 149-155 of 975")
	)
	(layers
		(0 "F.Cu" mixed)
		(4 "In1.Cu" power)
		(6 "In2.Cu" power)
		(8 "In3.Cu" mixed)
		(10 "In4.Cu" power)
		(12 "In5.Cu" mixed)
		(14 "In6.Cu" power)
		(16 "In7.Cu" mixed)
		(18 "In8.Cu" power)
		(2 "B.Cu" mixed)
		(9 "F.Adhes" user "F.Adhesive")
		(11 "B.Adhes" user "B.Adhesive")
		(13 "F.Paste" user)
		(15 "B.Paste" user)
		(5 "F.SilkS" user "F.Silkscreen")
		(7 "B.SilkS" user "B.Silkscreen")
		(1 "F.Mask" user)
		(3 "B.Mask" user)
		(17 "Dwgs.User" user "User.Drawings")
		(19 "Cmts.User" user "User.Comments")
		(21 "Eco1.User" user "User.Eco1")
		(23 "Eco2.User" user "User.Eco2")
		(25 "Edge.Cuts" user)
		(27 "Margin" user)
		(31 "F.CrtYd" user "F.Courtyard")
		(29 "B.CrtYd" user "B.Courtyard")
		(35 "F.Fab" user)
		(33 "B.Fab" user)
	)
	(footprint "antmicro-footprints:FB_0805_2012Metric"
		(layer "F.Cu")
		(at 232.9 179)
		(descr "FERRITE BEAD 0805")
		(tags "FERRITE BEAD 0805")
		(property "Reference" "FB1"
			(at -1 1.9 0)
			(layer "F.SilkS")
			(effects
				(font
					(size 0.7 0.7)
					(thickness 0.15)
				)
				(justify left bottom)
			)
		)
		(property "Value" "FB_220Z_2A_Murata-BLM21PG_0805"
			(at 0 1.8 0)
			(layer "F.Fab")
			(effects
				(font
					(size 0.7 0.7)
					(thickness 0.15)
				)
				(justify left bottom)
			)
		)
		(property "Description" "Ferrite Bead, 0805 [2012 Metric], 220 ohm, 2 A, BLM21, 0.045 ohm, ± 25%, DC power line"
			(at 0 0 0)
			(layer "F.Fab")
			(hide yes)
			(effects
				(font
					(size 1.27 1.27)
					(thickness 0.15)
				)
			)
		)
		(property "Author" "Antmicro"
			(at 0 0 0)
			(layer "F.Fab")
			(hide yes)
			(effects
				(font
					(size 1 1)
					(thickness 0.15)
				)
			)
		)
		(property "Current" ""
			(at 0 0 0)
			(layer "F.Fab")
			(hide yes)
			(effects
				(font
					(size 1 1)
					(thickness 0.15)
				)
			)
		)
		(property "License" "Apache-2.0"
			(at 0 0 0)
			(layer "F.Fab")
			(hide yes)
			(effects
				(font
					(size 1 1)
					(thickness 0.15)
				)
			)
		)
		(property "MPN" "BLM21PG221SN1D"
			(at 0 0 0)
			(layer "F.Fab")
			(hide yes)
			(effects
				(font
					(size 1 1)
					(thickness 0.15)
				)
			)
		)
		(property "Manufacturer" "Murata"
			(at 0 0 0)
			(layer "F.Fab")
			(hide yes)
			(effects
				(font
					(size 1 1)
					(thickness 0.15)
				)
			)
		)
		(property "Val" "220Z/2A"
			(at 0 0 0)
			(layer "F.Fab")
			(hide yes)
			(effects
				(font
					(size 1 1)
					(thickness 0.15)
				)
			)
		)
		(sheetname "Power supply")
		(sheetfile "power-supply.kicad_sch")
		(attr smd)
		(fp_line
			(start -0.319 0.698)
			(end 0.281 0.698)
			(stroke
				(width 0.15)
				(type solid)
			)
			(layer "F.SilkS")
		)
		(fp_line
			(start -0.299 -0.698)
			(end 0.299 -0.698)
			(stroke
				(width 0.15)
				(type solid)
			)
			(layer "F.SilkS")
		)
		(fp_rect
			(start 1.95 -0.9)
			(end -1.95 0.9)
			(stroke
				(width 0.05)
				(type default)
			)
			(fill no)
			(layer "F.CrtYd")
		)
		(fp_line
			(start -0.948 -0.681)
			(end 0.948 -0.681)
			(stroke
				(width 0.15)
				(type solid)
			)
			(layer "F.Fab")
		)
		(fp_line
			(start -0.948 -0.676)
			(end -0.948 0.676)
			(stroke
				(width 0.15)
				(type solid)
			)
			(layer "F.Fab")
		)
		(fp_line
			(start -0.948 0.681)
			(end 0.948 0.681)
			(stroke
				(width 0.15)
				(type solid)
			)
			(layer "F.Fab")
		)
		(fp_line
			(start 0.948 -0.676)
			(end 0.948 0.676)
			(stroke
				(width 0.15)
				(type solid)
			)
			(layer "F.Fab")
		)
		(pad "1" smd roundrect
			(at -1.1 0)
			(size 1.2 1.3)
			(layers "F.Cu" "F.Mask" "F.Paste")
			(roundrect_rratio 0.25)
			(net 757 "Net-(D4-Pad2)")
			(pintype "passive")
		)
		(pad "2" smd roundrect
			(at 1.1 0)
			(size 1.2 1.3)
			(layers "F.Cu" "F.Mask" "F.Paste")
			(roundrect_rratio 0.25)
			(net 698 "/Power supply/VDD")
			(pintype "passive")
		)
	)
	(footprint "antmicro-footprints:TP_SMD_0.75mm"
		(layer "F.Cu")
		(at 181.7 170.1492)
		(property "Reference" "TP8"
			(at 0.4 0.3508 0)
			(layer "F.SilkS")
			(effects
				(font
					(size 0.7 0.7)
					(thickness 0.15)
				)
				(justify left bottom)
			)
		)
		(property "Value" "TP_0.75mm_SMD"
			(at 0 1.2 0)
			(layer "F.Fab")
			(effects
				(font
					(size 0.7 0.7)
					(thickness 0.15)
				)
				(justify left bottom)
			)
		)
		(property "Description" "SMT test point"
			(at 0 0 0)
			(layer "F.Fab")
			(hide yes)
			(effects
				(font
					(size 1.27 1.27)
					(thickness 0.15)
				)
			)
		)
		(property "Author" "Antmicro"
			(at 0 0 0)
			(layer "F.Fab")
			(hide yes)
			(effects
				(font
					(size 1 1)
					(thickness 0.15)
				)
			)
		)
		(property "License" "Apache-2.0"
			(at 0 0 0)
			(layer "F.Fab")
			(hide yes)
			(effects
				(font
					(size 1 1)
					(thickness 0.15)
				)
			)
		)
		(property "MPN" ""
			(at 0 0 0)
			(layer "F.Fab")
			(hide yes)
			(effects
				(font
					(size 1 1)
					(thickness 0.15)
				)
			)
		)
		(property "Manufacturer" ""
			(at 0 0 0)
			(layer "F.Fab")
			(hide yes)
			(effects
				(font
					(size 1 1)
					(thickness 0.15)
				)
			)
		)
		(sheetname "DC-DC Converters")
		(sheetfile "dc-dc.kicad_sch")
		(attr exclude_from_pos_files)
		(pad "1" smd circle
			(at 0 0)
			(size 0.75 0.75)
			(layers "F.Cu" "F.Mask")
			(net 1393 "/I2C.QDCDC2_SCL")
			(pinfunction "1")
			(pintype "passive")
		)
	)
	(footprint "antmicro-footprints:C_0402_1005Metric"
		(layer "F.Cu")
		(at 155.07 139.2)
		(descr "Capacitor SMD 0402")
		(tags "capacitor SMD 0402")
		(property "Reference" "C348"
			(at -0.47 -0.2 45)
			(layer "F.SilkS")
			(effects
				(font
					(size 0.7 0.7)
					(thickness 0.15)
				)
				(justify left bottom)
			)
		)
		(property "Value" "C_1u_0402"
			(at 0 1.4 0)
			(layer "F.Fab")
			(effects
				(font
					(size 0.7 0.7)
					(thickness 0.15)
				)
				(justify left bottom)
			)
		)
		(property "Description" "SMD Multilayer Ceramic Capacitor, 1 µF, 10 V, 0402 [1005 Metric], ± 10%, X6S, C"
			(at 0 0 0)
			(layer "F.Fab")
			(hide yes)
			(effects
				(font
					(size 1.27 1.27)
					(thickness 0.15)
				)
			)
		)
		(property "Author" "Antmicro"
			(at 0 0 0)
			(layer "F.Fab")
			(hide yes)
			(effects
				(font
					(size 1 1)
					(thickness 0.15)
				)
			)
		)
		(property "Dielectric" ""
			(at 0 0 0)
			(layer "F.Fab")
			(hide yes)
			(effects
				(font
					(size 1 1)
					(thickness 0.15)
				)
			)
		)
		(property "License" "Apache-2.0"
			(at 0 0 0)
			(layer "F.Fab")
			(hide yes)
			(effects
				(font
					(size 1 1)
					(thickness 0.15)
				)
			)
		)
		(property "MPN" "C1005X6S1A105K050BC"
			(at 0 0 0)
			(layer "F.Fab")
			(hide yes)
			(effects
				(font
					(size 1 1)
					(thickness 0.15)
				)
			)
		)
		(property "Manufacturer" "TDK"
			(at 0 0 0)
			(layer "F.Fab")
			(hide yes)
			(effects
				(font
					(size 1 1)
					(thickness 0.15)
				)
			)
		)
		(property "Val" "1u"
			(at 0 0 0)
			(layer "F.Fab")
			(hide yes)
			(effects
				(font
					(size 1 1)
					(thickness 0.15)
				)
			)
		)
		(property "Voltage" ""
			(at 0 0 0)
			(layer "F.Fab")
			(hide yes)
			(effects
				(font
					(size 1 1)
					(thickness 0.15)
				)
			)
		)
		(sheetname "DC-DC Converters")
		(sheetfile "dc-dc.kicad_sch")
		(attr smd)
		(fp_rect
			(start -0.925 -0.47)
			(end 0.925 0.47)
			(stroke
				(width 0.05)
				(type default)
			)
			(fill no)
			(layer "F.CrtYd")
		)
		(fp_line
			(start -0.494 -0.25)
			(end 0.504 -0.25)
			(stroke
				(width 0.15)
				(type solid)
			)
			(layer "F.Fab")
		)
		(fp_line
			(start -0.494 0.248)
			(end -0.494 -0.25)
			(stroke
				(width 0.15)
				(type solid)
			)
			(layer "F.Fab")
		)
		(fp_line
			(start 0.504 -0.25)
			(end 0.504 0.248)
			(stroke
				(width 0.15)
				(type solid)
			)
			(layer "F.Fab")
		)
		(fp_line
			(start 0.504 0.248)
			(end -0.494 0.248)
			(stroke
				(width 0.15)
				(type solid)
			)
			(layer "F.Fab")
		)
		(pad "1" smd roundrect
			(at -0.48 0)
			(size 0.59 0.64)
			(layers "F.Cu" "F.Mask" "F.Paste")
			(roundrect_rratio 0.25)
			(net 1 "GND")
			(pintype "passive")
		)
		(pad "2" smd roundrect
			(at 0.48 0)
			(size 0.59 0.64)
			(layers "F.Cu" "F.Mask" "F.Paste")
			(roundrect_rratio 0.25)
			(net 743 "/DC-DC Converters/1V7")
			(pintype "passive")
		)
	)
	(footprint "antmicro-footprints:R_0402_1005Metric"
		(layer "F.Cu")
		(at 199.931 110.819)
		(descr "Resistor SMD 0402")
		(tags "resistor SMD 0402")
		(property "Reference" "R156"
			(at 0.869 0.381 0)
			(layer "F.SilkS")
			(effects
				(font
					(size 0.7 0.7)
					(thickness 0.15)
				)
				(justify left bottom)
			)
		)
		(property "Value" "R_10k_0402"
			(at 0 1.4 0)
			(layer "F.Fab")
			(effects
				(font
					(size 0.7 0.7)
					(thickness 0.15)
				)
				(justify left bottom)
			)
		)
		(property "Description" "SMD Chip Resistor, 10 kohm, ± 1%, 62.5 mW, 0402 [1005 Metric], Thick Film, General Purpose"
			(at 0 0 0)
			(layer "F.Fab")
			(hide yes)
			(effects
				(font
					(size 1.27 1.27)
					(thickness 0.15)
				)
			)
		)
		(property "Author" "Antmicro"
			(at 0 0 0)
			(layer "F.Fab")
			(hide yes)
			(effects
				(font
					(size 1 1)
					(thickness 0.15)
				)
			)
		)
		(property "License" "Apache-2.0"
			(at 0 0 0)
			(layer "F.Fab")
			(hide yes)
			(effects
				(font
					(size 1 1)
					(thickness 0.15)
				)
			)
		)
		(property "MPN" "CR0402-FX-1002GLF"
			(at 0 0 0)
			(layer "F.Fab")
			(hide yes)
			(effects
				(font
					(size 1 1)
					(thickness 0.15)
				)
			)
		)
		(property "Manufacturer" "Bourns"
			(at 0 0 0)
			(layer "F.Fab")
			(hide yes)
			(effects
				(font
					(size 1 1)
					(thickness 0.15)
				)
			)
		)
		(property "Tolerance" "1%"
			(at 0 0 0)
			(layer "F.Fab")
			(hide yes)
			(effects
				(font
					(size 1 1)
					(thickness 0.15)
				)
			)
		)
		(property "Val" "10k"
			(at 0 0 0)
			(layer "F.Fab")
			(hide yes)
			(effects
				(font
					(size 1 1)
					(thickness 0.15)
				)
			)
		)
		(sheetname "USB PHY")
		(sheetfile "usb-phy.kicad_sch")
		(attr smd)
		(fp_rect
			(start -0.925 -0.47)
			(end 0.925 0.47)
			(stroke
				(width 0.05)
				(type default)
			)
			(fill no)
			(layer "F.CrtYd")
		)
		(fp_rect
			(start -0.5 -0.25)
			(end 0.5 0.25)
			(stroke
				(width 0.15)
				(type solid)
			)
			(fill no)
			(layer "F.Fab")
		)
		(pad "1" smd roundrect
			(at -0.48 0)
			(size 0.59 0.64)
			(layers "F.Cu" "F.Mask" "F.Paste")
			(roundrect_rratio 0.25)
			(net 495 "/FPGA Bank 12 & 13/USB_HOST.INT")
			(pintype "passive")
		)
		(pad "2" smd roundrect
			(at 0.48 0)
			(size 0.59 0.64)
			(layers "F.Cu" "F.Mask" "F.Paste")
			(roundrect_rratio 0.25)
			(net 24 "+3V3")
			(pintype "passive")
		)
	)
	(footprint "antmicro-footprints:C_0402_1005Metric"
		(layer "F.Cu")
		(at 254.899 101 180)
		(descr "Capacitor SMD 0402")
		(tags "capacitor SMD 0402")
		(property "Reference" "C219"
			(at -1.451 -2.4 0)
			(layer "F.SilkS")
			(effects
				(font
					(size 0.7 0.7)
					(thickness 0.15)
				)
				(justify right bottom)
			)
		)
		(property "Value" "C_10u_0402"
			(at 0 1.4 0)
			(layer "F.Fab")
			(effects
				(font
					(size 0.7 0.7)
					(thickness 0.15)
				)
				(justify right bottom)
			)
		)
		(property "Description" "SMD Multilayer Ceramic Capacitor, 10 µF, 6.3 V, 0402 [1005 Metric], ± 20%, X5R, CC Series"
			(at 0 0 180)
			(layer "F.Fab")
			(hide yes)
			(effects
				(font
					(size 1.27 1.27)
					(thickness 0.15)
				)
			)
		)
		(property "Author" "Antmicro"
			(at 509.798 202 0)
			(layer "F.Fab")
			(hide yes)
			(effects
				(font
					(size 1 1)
					(thickness 0.15)
				)
			)
		)
		(property "Dielectric" ""
			(at 509.798 202 0)
			(layer "F.Fab")
			(hide yes)
			(effects
				(font
					(size 1 1)
					(thickness 0.15)
				)
			)
		)
		(property "License" "Apache-2.0"
			(at 509.798 202 0)
			(layer "F.Fab")
			(hide yes)
			(effects
				(font
					(size 1 1)
					(thickness 0.15)
				)
			)
		)
		(property "MPN" "CC0402MRX5R5BB106"
			(at 509.798 202 0)
			(layer "F.Fab")
			(hide yes)
			(effects
				(font
					(size 1 1)
					(thickness 0.15)
				)
			)
		)
		(property "Manufacturer" "YAGEO"
			(at 509.798 202 0)
			(layer "F.Fab")
			(hide yes)
			(effects
				(font
					(size 1 1)
					(thickness 0.15)
				)
			)
		)
		(property "Val" "10u"
			(at 509.798 202 0)
			(layer "F.Fab")
			(hide yes)
			(effects
				(font
					(size 1 1)
					(thickness 0.15)
				)
			)
		)
		(property "Voltage" ""
			(at 509.798 202 0)
			(layer "F.Fab")
			(hide yes)
			(effects
				(font
					(size 1 1)
					(thickness 0.15)
				)
			)
		)
		(sheetname "USB PHY")
		(sheetfile "usb-phy.kicad_sch")
		(attr smd)
		(fp_rect
			(start -0.925 -0.47)
			(end 0.925 0.47)
			(stroke
				(width 0.05)
				(type default)
			)
			(fill no)
			(layer "F.CrtYd")
		)
		(fp_line
			(start 0.504 0.248)
			(end -0.494 0.248)
			(stroke
				(width 0.15)
				(type solid)
			)
			(layer "F.Fab")
		)
		(fp_line
			(start 0.504 -0.25)
			(end 0.504 0.248)
			(stroke
				(width 0.15)
				(type solid)
			)
			(layer "F.Fab")
		)
		(fp_line
			(start -0.494 0.248)
			(end -0.494 -0.25)
			(stroke
				(width 0.15)
				(type solid)
			)
			(layer "F.Fab")
		)
		(fp_line
			(start -0.494 -0.25)
			(end 0.504 -0.25)
			(stroke
				(width 0.15)
				(type solid)
			)
			(layer "F.Fab")
		)
		(pad "1" smd roundrect
			(at -0.48 0 180)
			(size 0.59 0.64)
			(layers "F.Cu" "F.Mask" "F.Paste")
			(roundrect_rratio 0.25)
			(net 1 "GND")
			(pintype "passive")
		)
		(pad "2" smd roundrect
			(at 0.48 0 180)
			(size 0.59 0.64)
			(layers "F.Cu" "F.Mask" "F.Paste")
			(roundrect_rratio 0.25)
			(net 705 "/USB PHY/USB_HOST_VBUS")
			(pintype "passive")
		)
	)
	(footprint "antmicro-footprints:C_0402_1005Metric"
		(layer "F.Cu")
		(at 192.125 184.248999 -90)
		(descr "Capacitor SMD 0402")
		(tags "capacitor SMD 0402")
		(property "Reference" "C203"
			(at -1.298999 -1.275 90)
			(layer "F.SilkS")
			(effects
				(font
					(size 0.7 0.7)
					(thickness 0.15)
				)
				(justify right bottom)
			)
		)
		(property "Value" "C_100n_0402"
			(at 0 1.4 90)
			(layer "F.Fab")
			(effects
				(font
					(size 0.7 0.7)
					(thickness 0.15)
				)
				(justify right bottom)
			)
		)
		(property "Description" "SMD Multilayer Ceramic Capacitor, 0.1 µF, 50 V, 0402 [1005 Metric], ± 10%, X5R, GRM Series"
			(at 0 0 270)
			(layer "F.Fab")
			(hide yes)
			(effects
				(font
					(size 1.27 1.27)
					(thickness 0.15)
				)
			)
		)
		(property "Author" "Antmicro"
			(at 7.876001 376.373999 0)
			(layer "F.Fab")
			(hide yes)
			(effects
				(font
					(size 1 1)
					(thickness 0.15)
				)
			)
		)
		(property "Dielectric" "X5R"
			(at 7.876001 376.373999 0)
			(layer "F.Fab")
			(hide yes)
			(effects
				(font
					(size 1 1)
					(thickness 0.15)
				)
			)
		)
		(property "License" "Apache-2.0"
			(at 7.876001 376.373999 0)
			(layer "F.Fab")
			(hide yes)
			(effects
				(font
					(size 1 1)
					(thickness 0.15)
				)
			)
		)
		(property "MPN" "GRM155R61H104KE14D"
			(at 7.876001 376.373999 0)
			(layer "F.Fab")
			(hide yes)
			(effects
				(font
					(size 1 1)
					(thickness 0.15)
				)
			)
		)
		(property "Manufacturer" "Murata"
			(at 7.876001 376.373999 0)
			(layer "F.Fab")
			(hide yes)
			(effects
				(font
					(size 1 1)
					(thickness 0.15)
				)
			)
		)
		(property "Val" "100n"
			(at 7.876001 376.373999 0)
			(layer "F.Fab")
			(hide yes)
			(effects
				(font
					(size 1 1)
					(thickness 0.15)
				)
			)
		)
		(property "Voltage" "50V"
			(at 7.876001 376.373999 0)
			(layer "F.Fab")
			(hide yes)
			(effects
				(font
					(size 1 1)
					(thickness 0.15)
				)
			)
		)
		(sheetname "Power supply")
		(sheetfile "power-supply.kicad_sch")
		(attr smd)
		(fp_rect
			(start -0.925 -0.47)
			(end 0.925 0.47)
			(stroke
				(width 0.05)
				(type default)
			)
			(fill no)
			(layer "F.CrtYd")
		)
		(fp_line
			(start -0.494 0.248)
			(end -0.494 -0.25)
			(stroke
				(width 0.15)
				(type solid)
			)
			(layer "F.Fab")
		)
		(fp_line
			(start 0.504 0.248)
			(end -0.494 0.248)
			(stroke
				(width 0.15)
				(type solid)
			)
			(layer "F.Fab")
		)
		(fp_line
			(start -0.494 -0.25)
			(end 0.504 -0.25)
			(stroke
				(width 0.15)
				(type solid)
			)
			(layer "F.Fab")
		)
		(fp_line
			(start 0.504 -0.25)
			(end 0.504 0.248)
			(stroke
				(width 0.15)
				(type solid)
			)
			(layer "F.Fab")
		)
		(pad "1" smd roundrect
			(at -0.48 0 270)
			(size 0.59 0.64)
			(layers "F.Cu" "F.Mask" "F.Paste")
			(roundrect_rratio 0.25)
			(net 1 "GND")
			(pintype "passive")
		)
		(pad "2" smd roundrect
			(at 0.48 0 270)
			(size 0.59 0.64)
			(layers "F.Cu" "F.Mask" "F.Paste")
			(roundrect_rratio 0.25)
			(net 4 "/Power supply/DC_IN")
			(pintype "passive")
		)
	)
	(footprint "antmicro-footprints:R_0402_1005Metric"
		(layer "F.Cu")
		(at 236.35 145.45 180)
		(descr "Resistor SMD 0402")
		(tags "resistor SMD 0402")
		(property "Reference" "R183"
			(at 1.05 -4.45 180)
			(layer "F.SilkS")
			(effects
				(font
					(size 0.7 0.7)
					(thickness 0.15)
				)
				(justify left bottom)
			)
		)
		(property "Value" "R_33R_0402"
			(at 0 1.4 180)
			(layer "F.Fab")
			(effects
				(font
					(size 0.7 0.7)
					(thickness 0.15)
				)
				(justify left bottom)
			)
		)
		(property "Description" "SMD Chip Resistor, 33 ohm, ± 1%, 62.5 mW, 0402 [1005 Metric], Thick Film, General Purpose"
			(at 0 0 180)
			(layer "F.Fab")
			(hide yes)
			(effects
				(font
					(size 1.27 1.27)
					(thickness 0.15)
				)
			)
		)
		(property "Author" "Antmicro"
			(at 472.7 290.9 0)
			(layer "F.Fab")
			(hide yes)
			(effects
				(font
					(size 1 1)
					(thickness 0.15)
				)
			)
		)
		(property "License" "Apache-2.0"
			(at 472.7 290.9 0)
			(layer "F.Fab")
			(hide yes)
			(effects
				(font
					(size 1 1)
					(thickness 0.15)
				)
			)
		)
		(property "MPN" "CR0402-FX-33R0GLF"
			(at 472.7 290.9 0)
			(layer "F.Fab")
			(hide yes)
			(effects
				(font
					(size 1 1)
					(thickness 0.15)
				)
			)
		)
		(property "Manufacturer" "Bourns"
			(at 472.7 290.9 0)
			(layer "F.Fab")
			(hide yes)
			(effects
				(font
					(size 1 1)
					(thickness 0.15)
				)
			)
		)
		(property "Tolerance" "1%"
			(at 472.7 290.9 0)
			(layer "F.Fab")
			(hide yes)
			(effects
				(font
					(size 1 1)
					(thickness 0.15)
				)
			)
		)
		(property "Val" "33R"
			(at 472.7 290.9 0)
			(layer "F.Fab")
			(hide yes)
			(effects
				(font
					(size 1 1)
					(thickness 0.15)
				)
			)
		)
		(sheetname "USB PHY")
		(sheetfile "usb-phy.kicad_sch")
		(attr smd)
		(fp_rect
			(start -0.925 -0.47)
			(end 0.925 0.47)
			(stroke
				(width 0.05)
				(type default)
			)
			(fill no)
			(layer "F.CrtYd")
		)
		(fp_rect
			(start -0.5 -0.25)
			(end 0.5 0.25)
			(stroke
				(width 0.15)
				(type solid)
			)
			(fill no)
			(layer "F.Fab")
		)
		(pad "1" smd roundrect
			(at -0.48 0 180)
			(size 0.59 0.64)
			(layers "F.Cu" "F.Mask" "F.Paste")
			(roundrect_rratio 0.25)
			(net 375 "Net-(U23-B2Y)")
			(pintype "passive")
		)
		(pad "2" smd roundrect
			(at 0.48 0 180)
			(size 0.59 0.64)
			(layers "F.Cu" "F.Mask" "F.Paste")
			(roundrect_rratio 0.25)
			(net 1295 "/USB_SPI.MOSI")
			(pintype "passive")
		)
	)
)
